# T6G (Grand Teton) — schematic netlist excerpt (pin names and nets, part order shuffled) for the footprints in the layout excerpt that follows; sources: Cadence DE-HDL packaged netlist, KiCad conversion of 04192023_DAF0TMB3IC0_F0TG_MB_C_brd_V02_OCP.brd

PR6505  Q_RES  20K 1% CHIP  pkg 0402LF  page 360 : A = P1V8_RETIMER_CPU0_FB ; B = P1V8_CPU0_RT_1D
C1279  Q_CAP  0.1UF 25V 10% X7R  pkg 0402  page 145 : A = P12V_E1S_0_R ; B = GND

(kicad_pcb
	(version 20260206)
	(generator "pcbnew")
	(generator_version "10.0")
	(general
		(thickness 1.6)
		(legacy_teardrops no)
	)
	(paper "A4")
	(title_block
		(title "04192023_DAF0TMB3IC0_F0TG_MB_C_brd_V02_OCP.brd")
		(comment 1 "Grand Teton / footprints 2620-2622 of 8354")
	)
	(layers
		(0 "F.Cu" signal "TOP")
		(4 "In1.Cu" signal "GND")
		(6 "In2.Cu" signal "IN1")
		(8 "In3.Cu" signal "GND1")
		(10 "In4.Cu" signal "IN2")
		(12 "In5.Cu" signal "GND2")
		(14 "In6.Cu" signal "IN3")
		(16 "In7.Cu" signal "GND3")
		(18 "In8.Cu" signal "VCC")
		(20 "In9.Cu" signal "VCC1")
		(22 "In10.Cu" signal "GND4")
		(24 "In11.Cu" signal "IN4")
		(26 "In12.Cu" signal "GND5")
		(28 "In13.Cu" signal "IN5")
		(30 "In14.Cu" signal "GND6")
		(32 "In15.Cu" signal "IN6")
		(34 "In16.Cu" signal "GND7")
		(2 "B.Cu" signal "BOTTOM")
		(9 "F.Adhes" user "F.Adhesive")
		(11 "B.Adhes" user "B.Adhesive")
		(13 "F.Paste" user "Package Geometry/Pastemask Top")
		(15 "B.Paste" user "Package Geometry/Pastemask Bottom")
		(5 "F.SilkS" user "Ref Des/Silkscreen Top")
		(7 "B.SilkS" user "Ref Des/Silkscreen Bottom")
		(1 "F.Mask" user "Board Geometry/Soldermask Top")
		(3 "B.Mask" user "Board Geometry/Soldermask Bottom")
		(17 "Dwgs.User" user "User.Drawings")
		(19 "Cmts.User" user "User.Comments")
		(21 "Eco1.User" user "User.Eco1")
		(23 "Eco2.User" user "User.Eco2")
		(25 "Edge.Cuts" user "Board Geometry/Outline")
		(27 "Margin" user)
		(31 "F.CrtYd" user "Package Geometry/Place Bound Top")
		(29 "B.CrtYd" user "Package Geometry/Place Bound Bottom")
		(35 "F.Fab" user "Ref Des/Assembly Top")
		(33 "B.Fab" user "Ref Des/Assembly Bottom")
	)
	(footprint ""
		(layer "F.Cu")
		(at 25.638506 19.444716 -90)
		(property "Reference" "BATTERY_BT2"
			(at 0 0 270)
			(layer "F.SilkS")
			(hide yes)
			(effects
				(font
					(size 1.27 1.27)
				)
			)
		)
		(property "Value" ""
			(at 0 0 270)
			(layer "F.Fab")
			(effects
				(font
					(size 1.27 1.27)
				)
			)
		)
		(duplicate_pad_numbers_are_jumpers no)
		(pad "1" smd circle
			(at 0 0 270)
			(size 0.762 0.762)
			(layers "F.Cu" "F.Mask" "F.Paste")
			(net "Net_2616")
		)
	)
	(footprint ""
		(layer "F.Cu")
		(at 238.859822 -290.341812 90)
		(property "Reference" "PR6505"
			(at 0 0 90)
			(layer "F.SilkS")
			(hide yes)
			(effects
				(font
					(size 1.27 1.27)
				)
			)
		)
		(property "Value" ""
			(at 0 0 90)
			(layer "F.Fab")
			(effects
				(font
					(size 1.27 1.27)
				)
			)
		)
		(duplicate_pad_numbers_are_jumpers no)
		(fp_line
			(start 0.7874 -0.4064)
			(end 0.7874 0.4064)
			(stroke
				(width 0.1524)
				(type default)
			)
			(layer "F.SilkS")
		)
		(fp_line
			(start -0.7874 -0.4064)
			(end 0.7874 -0.4064)
			(stroke
				(width 0.1524)
				(type default)
			)
			(layer "F.SilkS")
		)
		(fp_line
			(start 0.7874 0.4064)
			(end -0.7874 0.4064)
			(stroke
				(width 0.1524)
				(type default)
			)
			(layer "F.SilkS")
		)
		(fp_line
			(start -0.7874 0.4064)
			(end -0.7874 -0.4064)
			(stroke
				(width 0.1524)
				(type default)
			)
			(layer "F.SilkS")
		)
		(fp_line
			(start -0.12065 -0.305054)
			(end -0.12065 -0.2794)
			(stroke
				(width 0.1)
				(type default)
			)
			(layer "F.Fab")
		)
		(fp_line
			(start -0.67945 -0.305054)
			(end -0.12065 -0.305054)
			(stroke
				(width 0.1)
				(type default)
			)
			(layer "F.Fab")
		)
		(fp_line
			(start 0.67945 -0.3048)
			(end 0.67945 0.3048)
			(stroke
				(width 0.1)
				(type default)
			)
			(layer "F.Fab")
		)
		(fp_line
			(start 0.12065 -0.3048)
			(end 0.67945 -0.3048)
			(stroke
				(width 0.1)
				(type default)
			)
			(layer "F.Fab")
		)
		(fp_line
			(start 0.12065 -0.2794)
			(end 0.12065 -0.3048)
			(stroke
				(width 0.1)
				(type default)
			)
			(layer "F.Fab")
		)
		(fp_line
			(start -0.12065 -0.2794)
			(end 0.12065 -0.2794)
			(stroke
				(width 0.1)
				(type default)
			)
			(layer "F.Fab")
		)
		(fp_line
			(start 0.120396 0.2794)
			(end -0.12065 0.2794)
			(stroke
				(width 0.1)
				(type default)
			)
			(layer "F.Fab")
		)
		(fp_line
			(start -0.12065 0.2794)
			(end -0.12065 0.3048)
			(stroke
				(width 0.1)
				(type default)
			)
			(layer "F.Fab")
		)
		(fp_line
			(start 0.67945 0.3048)
			(end 0.120396 0.3048)
			(stroke
				(width 0.1)
				(type default)
			)
			(layer "F.Fab")
		)
		(fp_line
			(start 0.120396 0.3048)
			(end 0.120396 0.2794)
			(stroke
				(width 0.1)
				(type default)
			)
			(layer "F.Fab")
		)
		(fp_line
			(start -0.12065 0.3048)
			(end -0.67945 0.3048)
			(stroke
				(width 0.1)
				(type default)
			)
			(layer "F.Fab")
		)
		(fp_line
			(start -0.67945 0.3048)
			(end -0.67945 -0.305054)
			(stroke
				(width 0.1)
				(type default)
			)
			(layer "F.Fab")
		)
		(pad "1" smd circle
			(at -0.40005 0 90)
			(size 0 0)
			(layers "F.Cu" "F.Mask" "F.Paste")
			(net "P1V8_RETIMER_CPU0_FB")
		)
		(pad "2" smd circle
			(at 0.40005 0 90)
			(size 0 0)
			(layers "F.Cu" "F.Mask" "F.Paste")
			(net "P1V8_CPU0_RT_1D")
		)
	)
	(footprint ""
		(layer "F.Cu")
		(at 245.222268 -42.26179 -90)
		(property "Reference" "C1279"
			(at 0 0 270)
			(layer "F.SilkS")
			(hide yes)
			(effects
				(font
					(size 1.27 1.27)
				)
			)
		)
		(property "Value" ""
			(at 0 0 270)
			(layer "F.Fab")
			(effects
				(font
					(size 1.27 1.27)
				)
			)
		)
		(duplicate_pad_numbers_are_jumpers no)
		(fp_line
			(start -0.7874 0.4064)
			(end -0.7874 -0.4064)
			(stroke
				(width 0.1524)
				(type default)
			)
			(layer "F.SilkS")
		)
		(fp_line
			(start 0.7874 0.4064)
			(end -0.7874 0.4064)
			(stroke
				(width 0.1524)
				(type default)
			)
			(layer "F.SilkS")
		)
		(fp_line
			(start -0.7874 -0.4064)
			(end 0.7874 -0.4064)
			(stroke
				(width 0.1524)
				(type default)
			)
			(layer "F.SilkS")
		)
		(fp_line
			(start 0.7874 -0.4064)
			(end 0.7874 0.4064)
			(stroke
				(width 0.1524)
				(type default)
			)
			(layer "F.SilkS")
		)
		(fp_line
			(start -0.67945 0.3048)
			(end -0.67945 -0.305054)
			(stroke
				(width 0.1)
				(type default)
			)
			(layer "F.Fab")
		)
		(fp_line
			(start -0.12065 0.3048)
			(end -0.67945 0.3048)
			(stroke
				(width 0.1)
				(type default)
			)
			(layer "F.Fab")
		)
		(fp_line
			(start 0.120396 0.3048)
			(end 0.120396 0.2794)
			(stroke
				(width 0.1)
				(type default)
			)
			(layer "F.Fab")
		)
		(fp_line
			(start 0.67945 0.3048)
			(end 0.120396 0.3048)
			(stroke
				(width 0.1)
				(type default)
			)
			(layer "F.Fab")
		)
		(fp_line
			(start -0.12065 0.2794)
			(end -0.12065 0.3048)
			(stroke
				(width 0.1)
				(type default)
			)
			(layer "F.Fab")
		)
		(fp_line
			(start 0.120396 0.2794)
			(end -0.12065 0.2794)
			(stroke
				(width 0.1)
				(type default)
			)
			(layer "F.Fab")
		)
		(fp_line
			(start -0.12065 -0.2794)
			(end 0.12065 -0.2794)
			(stroke
				(width 0.1)
				(type default)
			)
			(layer "F.Fab")
		)
		(fp_line
			(start 0.12065 -0.2794)
			(end 0.12065 -0.3048)
			(stroke
				(width 0.1)
				(type default)
			)
			(layer "F.Fab")
		)
		(fp_line
			(start 0.12065 -0.3048)
			(end 0.67945 -0.3048)
			(stroke
				(width 0.1)
				(type default)
			)
			(layer "F.Fab")
		)
		(fp_line
			(start 0.67945 -0.3048)
			(end 0.67945 0.3048)
			(stroke
				(width 0.1)
				(type default)
			)
			(layer "F.Fab")
		)
		(fp_line
			(start -0.67945 -0.305054)
			(end -0.12065 -0.305054)
			(stroke
				(width 0.1)
				(type default)
			)
			(layer "F.Fab")
		)
		(fp_line
			(start -0.12065 -0.305054)
			(end -0.12065 -0.2794)
			(stroke
				(width 0.1)
				(type default)
			)
			(layer "F.Fab")
		)
		(pad "1" smd circle
			(at -0.40005 0 270)
			(size 0 0)
			(layers "F.Cu" "F.Mask" "F.Paste")
			(net "P12V_E1S_0_R")
		)
		(pad "2" smd circle
			(at 0.40005 0 270)
			(size 0 0)
			(layers "F.Cu" "F.Mask" "F.Paste")
			(net "GND")
		)
	)
)
